(kicad_pcb
	(version 20260206)
	(generator "pcbnew")
	(generator_version "10.0")
	(general
		(thickness 1.6)
		(legacy_teardrops no)
	)
	(paper "A4")
	(title_block
		(title "01162023_DA0F0TEBIF0_F0T_Expander_BD_F_brd_V02_OCP.brd")
		(comment 1 "Grand Teton / footprints 4215-4220 of 9728")
	)
	(layers
		(0 "F.Cu" signal "TOP")
		(4 "In1.Cu" signal "GND")
		(6 "In2.Cu" signal "VCC")
		(8 "In3.Cu" signal "VCC1")
		(10 "In4.Cu" signal "GND1")
		(12 "In5.Cu" signal "IN1")
		(14 "In6.Cu" signal "GND2")
		(16 "In7.Cu" signal "IN2")
		(18 "In8.Cu" signal "GND3")
		(20 "In9.Cu" signal "IN3")
		(22 "In10.Cu" signal "GND4")
		(24 "In11.Cu" signal "IN4")
		(26 "In12.Cu" signal "GND5")
		(28 "In13.Cu" signal "IN5")
		(30 "In14.Cu" signal "GND6")
		(32 "In15.Cu" signal "IN6")
		(34 "In16.Cu" signal "GND7")
		(2 "B.Cu" signal "BOTTOM")
		(9 "F.Adhes" user "F.Adhesive")
		(11 "B.Adhes" user "B.Adhesive")
		(13 "F.Paste" user "Package Geometry/Pastemask Top")
		(15 "B.Paste" user "Package Geometry/Pastemask Bottom")
		(5 "F.SilkS" user "Ref Des/Silkscreen Top")
		(7 "B.SilkS" user "Ref Des/Silkscreen Bottom")
		(1 "F.Mask" user "Board Geometry/Soldermask Top")
		(3 "B.Mask" user "Board Geometry/Soldermask Bottom")
		(17 "Dwgs.User" user "User.Drawings")
		(19 "Cmts.User" user "User.Comments")
		(21 "Eco1.User" user "User.Eco1")
		(23 "Eco2.User" user "User.Eco2")
		(25 "Edge.Cuts" user "Board Geometry/Outline")
		(27 "Margin" user)
		(31 "F.CrtYd" user "Package Geometry/Place Bound Top")
		(29 "B.CrtYd" user "Package Geometry/Place Bound Bottom")
		(35 "F.Fab" user "Ref Des/Assembly Top")
		(33 "B.Fab" user "Ref Des/Assembly Bottom")
	)
	(footprint ""
		(layer "F.Cu")
		(at 358.013 -225.552)
		(property "Reference" "R3631"
			(at 0 0 0)
			(layer "F.SilkS")
			(hide yes)
			(effects
				(font
					(size 1.27 1.27)
				)
			)
		)
		(property "Value" ""
			(at 0 0 0)
			(layer "F.Fab")
			(effects
				(font
					(size 1.27 1.27)
				)
			)
		)
		(duplicate_pad_numbers_are_jumpers no)
		(fp_line
			(start -0.7874 -0.4064)
			(end 0.7874 -0.4064)
			(stroke
				(width 0.1524)
				(type default)
			)
			(layer "F.SilkS")
		)
		(fp_line
			(start -0.7874 0.4064)
			(end -0.7874 -0.4064)
			(stroke
				(width 0.1524)
				(type default)
			)
			(layer "F.SilkS")
		)
		(fp_line
			(start 0.7874 -0.4064)
			(end 0.7874 0.4064)
			(stroke
				(width 0.1524)
				(type default)
			)
			(layer "F.SilkS")
		)
		(fp_line
			(start 0.7874 0.4064)
			(end -0.7874 0.4064)
			(stroke
				(width 0.1524)
				(type default)
			)
			(layer "F.SilkS")
		)
		(fp_line
			(start -0.67945 -0.305054)
			(end -0.12065 -0.305054)
			(stroke
				(width 0.1)
				(type default)
			)
			(layer "F.Fab")
		)
		(fp_line
			(start -0.67945 0.3048)
			(end -0.67945 -0.305054)
			(stroke
				(width 0.1)
				(type default)
			)
			(layer "F.Fab")
		)
		(fp_line
			(start -0.12065 -0.305054)
			(end -0.12065 -0.2794)
			(stroke
				(width 0.1)
				(type default)
			)
			(layer "F.Fab")
		)
		(fp_line
			(start -0.12065 -0.2794)
			(end 0.12065 -0.2794)
			(stroke
				(width 0.1)
				(type default)
			)
			(layer "F.Fab")
		)
		(fp_line
			(start -0.12065 0.2794)
			(end -0.12065 0.3048)
			(stroke
				(width 0.1)
				(type default)
			)
			(layer "F.Fab")
		)
		(fp_line
			(start -0.12065 0.3048)
			(end -0.67945 0.3048)
			(stroke
				(width 0.1)
				(type default)
			)
			(layer "F.Fab")
		)
		(fp_line
			(start 0.120396 0.2794)
			(end -0.12065 0.2794)
			(stroke
				(width 0.1)
				(type default)
			)
			(layer "F.Fab")
		)
		(fp_line
			(start 0.120396 0.3048)
			(end 0.120396 0.2794)
			(stroke
				(width 0.1)
				(type default)
			)
			(layer "F.Fab")
		)
		(fp_line
			(start 0.12065 -0.3048)
			(end 0.67945 -0.3048)
			(stroke
				(width 0.1)
				(type default)
			)
			(layer "F.Fab")
		)
		(fp_line
			(start 0.12065 -0.2794)
			(end 0.12065 -0.3048)
			(stroke
				(width 0.1)
				(type default)
			)
			(layer "F.Fab")
		)
		(fp_line
			(start 0.67945 -0.3048)
			(end 0.67945 0.3048)
			(stroke
				(width 0.1)
				(type default)
			)
			(layer "F.Fab")
		)
		(fp_line
			(start 0.67945 0.3048)
			(end 0.120396 0.3048)
			(stroke
				(width 0.1)
				(type default)
			)
			(layer "F.Fab")
		)
		(pad "1" smd circle
			(at -0.40005 0)
			(size 0 0)
			(layers "F.Cu" "F.Mask" "F.Paste")
			(net "RST_NIC3_PERST_N")
		)
		(pad "2" smd circle
			(at 0.40005 0)
			(size 0 0)
			(layers "F.Cu" "F.Mask" "F.Paste")
			(net "RST_NIC3_PERST_R_N")
		)
	)
	(footprint ""
		(layer "F.Cu")
		(at 334.493362 -93.152214 -90)
		(property "Reference" "R3508"
			(at 0 0 270)
			(layer "F.SilkS")
			(hide yes)
			(effects
				(font
					(size 1.27 1.27)
				)
			)
		)
		(property "Value" ""
			(at 0 0 270)
			(layer "F.Fab")
			(effects
				(font
					(size 1.27 1.27)
				)
			)
		)
		(duplicate_pad_numbers_are_jumpers no)
		(fp_line
			(start -0.7874 0.4064)
			(end -0.7874 -0.4064)
			(stroke
				(width 0.1524)
				(type default)
			)
			(layer "F.SilkS")
		)
		(fp_line
			(start 0.7874 0.4064)
			(end -0.7874 0.4064)
			(stroke
				(width 0.1524)
				(type default)
			)
			(layer "F.SilkS")
		)
		(fp_line
			(start -0.7874 -0.4064)
			(end 0.7874 -0.4064)
			(stroke
				(width 0.1524)
				(type default)
			)
			(layer "F.SilkS")
		)
		(fp_line
			(start 0.7874 -0.4064)
			(end 0.7874 0.4064)
			(stroke
				(width 0.1524)
				(type default)
			)
			(layer "F.SilkS")
		)
		(fp_line
			(start -0.67945 0.3048)
			(end -0.67945 -0.305054)
			(stroke
				(width 0.1)
				(type default)
			)
			(layer "F.Fab")
		)
		(fp_line
			(start -0.12065 0.3048)
			(end -0.67945 0.3048)
			(stroke
				(width 0.1)
				(type default)
			)
			(layer "F.Fab")
		)
		(fp_line
			(start 0.120396 0.3048)
			(end 0.120396 0.2794)
			(stroke
				(width 0.1)
				(type default)
			)
			(layer "F.Fab")
		)
		(fp_line
			(start 0.67945 0.3048)
			(end 0.120396 0.3048)
			(stroke
				(width 0.1)
				(type default)
			)
			(layer "F.Fab")
		)
		(fp_line
			(start -0.12065 0.2794)
			(end -0.12065 0.3048)
			(stroke
				(width 0.1)
				(type default)
			)
			(layer "F.Fab")
		)
		(fp_line
			(start 0.120396 0.2794)
			(end -0.12065 0.2794)
			(stroke
				(width 0.1)
				(type default)
			)
			(layer "F.Fab")
		)
		(fp_line
			(start -0.12065 -0.2794)
			(end 0.12065 -0.2794)
			(stroke
				(width 0.1)
				(type default)
			)
			(layer "F.Fab")
		)
		(fp_line
			(start 0.12065 -0.2794)
			(end 0.12065 -0.3048)
			(stroke
				(width 0.1)
				(type default)
			)
			(layer "F.Fab")
		)
		(fp_line
			(start 0.12065 -0.3048)
			(end 0.67945 -0.3048)
			(stroke
				(width 0.1)
				(type default)
			)
			(layer "F.Fab")
		)
		(fp_line
			(start 0.67945 -0.3048)
			(end 0.67945 0.3048)
			(stroke
				(width 0.1)
				(type default)
			)
			(layer "F.Fab")
		)
		(fp_line
			(start -0.67945 -0.305054)
			(end -0.12065 -0.305054)
			(stroke
				(width 0.1)
				(type default)
			)
			(layer "F.Fab")
		)
		(fp_line
			(start -0.12065 -0.305054)
			(end -0.12065 -0.2794)
			(stroke
				(width 0.1)
				(type default)
			)
			(layer "F.Fab")
		)
		(pad "1" smd circle
			(at -0.40005 0 270)
			(size 0 0)
			(layers "F.Cu" "F.Mask" "F.Paste")
			(net "P3V3")
		)
		(pad "2" smd circle
			(at 0.40005 0 270)
			(size 0 0)
			(layers "F.Cu" "F.Mask" "F.Paste")
			(net "PU_9ZXL0851_8_15_HBW")
		)
	)
	(footprint ""
		(layer "F.Cu")
		(at 263.789414 -63.56223)
		(property "Reference" "Q205"
			(at 0.150368 -2.585212 0)
			(unlocked yes)
			(layer "F.SilkS")
			(effects
				(font
					(size 0.7874 0.5842)
					(thickness 0.1524)
				)
			)
		)
		(property "Value" ""
			(at 0 0 0)
			(layer "F.Fab")
			(effects
				(font
					(size 1.27 1.27)
				)
			)
		)
		(duplicate_pad_numbers_are_jumpers no)
		(fp_line
			(start -1.376172 -1.199896)
			(end -0.508 -1.199896)
			(stroke
				(width 0.1524)
				(type default)
			)
			(layer "F.SilkS")
		)
		(fp_line
			(start -1.376172 1.199896)
			(end -1.376172 -1.199896)
			(stroke
				(width 0.1524)
				(type default)
			)
			(layer "F.SilkS")
		)
		(fp_line
			(start -0.508 -1.199896)
			(end 0 -0.762)
			(stroke
				(width 0.1524)
				(type default)
			)
			(layer "F.SilkS")
		)
		(fp_line
			(start 0 -0.762)
			(end 0.508 -1.199896)
			(stroke
				(width 0.1524)
				(type default)
			)
			(layer "F.SilkS")
		)
		(fp_line
			(start 0.508 -1.199896)
			(end 1.376172 -1.199896)
			(stroke
				(width 0.1524)
				(type default)
			)
			(layer "F.SilkS")
		)
		(fp_line
			(start 1.376172 -1.199896)
			(end 1.376172 1.199896)
			(stroke
				(width 0.1524)
				(type default)
			)
			(layer "F.SilkS")
		)
		(fp_line
			(start 1.376172 1.199896)
			(end -1.376172 1.199896)
			(stroke
				(width 0.1524)
				(type default)
			)
			(layer "F.SilkS")
		)
		(fp_poly
			(pts
				(xy -1.606042 -1.021334) (xy -1.875536 -1.829562) (xy -2.41427 -1.290574)
			)
			(stroke
				(width 0)
				(type default)
			)
			(fill yes)
			(layer "F.SilkS")
		)
		(fp_line
			(start -0.674878 -1.100074)
			(end 0.674878 -1.100074)
			(stroke
				(width 0.1)
				(type default)
			)
			(layer "F.Fab")
		)
		(fp_line
			(start -0.674878 1.100074)
			(end -0.674878 -1.100074)
			(stroke
				(width 0.1)
				(type default)
			)
			(layer "F.Fab")
		)
		(fp_line
			(start 0.674878 -1.100074)
			(end 0.674878 1.100074)
			(stroke
				(width 0.1)
				(type default)
			)
			(layer "F.Fab")
		)
		(fp_line
			(start 0.674878 1.100074)
			(end -0.674878 1.100074)
			(stroke
				(width 0.1)
				(type default)
			)
			(layer "F.Fab")
		)
		(fp_poly
			(pts
				(xy -1.4605 -0.7493) (xy -2.2225 -1.1303) (xy -2.2225 -0.3683)
			)
			(stroke
				(width 0)
				(type default)
			)
			(fill yes)
			(layer "F.Fab")
		)
		(pad "1" smd rect
			(at -0.899922 -0.750062 270)
			(size 0.6096 0.6096)
			(layers "F.Cu" "F.Mask" "F.Paste")
			(net "GND")
		)
		(pad "2" smd rect
			(at -0.899922 0 270)
			(size 0.4064 0.6096)
			(layers "F.Cu" "F.Mask" "F.Paste")
			(net "P12V_SSD9_PG_G1")
		)
		(pad "3" smd rect
			(at -0.899922 0.750062 270)
			(size 0.6096 0.6096)
			(layers "F.Cu" "F.Mask" "F.Paste")
			(net "PWRGD_P12V_SSD9_D")
		)
		(pad "4" smd rect
			(at 0.899922 0.750062 270)
			(size 0.6096 0.6096)
			(layers "F.Cu" "F.Mask" "F.Paste")
			(net "GND")
		)
		(pad "5" smd rect
			(at 0.899922 0 270)
			(size 0.4064 0.6096)
			(layers "F.Cu" "F.Mask" "F.Paste")
			(net "P12V_SSD9_PG_G2")
		)
		(pad "6" smd rect
			(at 0.899922 -0.750062 270)
			(size 0.6096 0.6096)
			(layers "F.Cu" "F.Mask" "F.Paste")
			(net "P12V_SSD9_PG_G2")
		)
	)
	(footprint ""
		(layer "F.Cu")
		(at 231.3686 -231.394 90)
		(property "Reference" "R4525"
			(at 0 0 90)
			(layer "F.SilkS")
			(hide yes)
			(effects
				(font
					(size 1.27 1.27)
				)
			)
		)
		(property "Value" ""
			(at 0 0 90)
			(layer "F.Fab")
			(effects
				(font
					(size 1.27 1.27)
				)
			)
		)
		(duplicate_pad_numbers_are_jumpers no)
		(fp_line
			(start 0.7874 -0.4064)
			(end 0.7874 0.4064)
			(stroke
				(width 0.1524)
				(type default)
			)
			(layer "F.SilkS")
		)
		(fp_line
			(start -0.7874 -0.4064)
			(end 0.7874 -0.4064)
			(stroke
				(width 0.1524)
				(type default)
			)
			(layer "F.SilkS")
		)
		(fp_line
			(start 0.7874 0.4064)
			(end -0.7874 0.4064)
			(stroke
				(width 0.1524)
				(type default)
			)
			(layer "F.SilkS")
		)
		(fp_line
			(start -0.7874 0.4064)
			(end -0.7874 -0.4064)
			(stroke
				(width 0.1524)
				(type default)
			)
			(layer "F.SilkS")
		)
		(fp_line
			(start -0.12065 -0.305054)
			(end -0.12065 -0.2794)
			(stroke
				(width 0.1)
				(type default)
			)
			(layer "F.Fab")
		)
		(fp_line
			(start -0.67945 -0.305054)
			(end -0.12065 -0.305054)
			(stroke
				(width 0.1)
				(type default)
			)
			(layer "F.Fab")
		)
		(fp_line
			(start 0.67945 -0.3048)
			(end 0.67945 0.3048)
			(stroke
				(width 0.1)
				(type default)
			)
			(layer "F.Fab")
		)
		(fp_line
			(start 0.12065 -0.3048)
			(end 0.67945 -0.3048)
			(stroke
				(width 0.1)
				(type default)
			)
			(layer "F.Fab")
		)
		(fp_line
			(start 0.12065 -0.2794)
			(end 0.12065 -0.3048)
			(stroke
				(width 0.1)
				(type default)
			)
			(layer "F.Fab")
		)
		(fp_line
			(start -0.12065 -0.2794)
			(end 0.12065 -0.2794)
			(stroke
				(width 0.1)
				(type default)
			)
			(layer "F.Fab")
		)
		(fp_line
			(start 0.120396 0.2794)
			(end -0.12065 0.2794)
			(stroke
				(width 0.1)
				(type default)
			)
			(layer "F.Fab")
		)
		(fp_line
			(start -0.12065 0.2794)
			(end -0.12065 0.3048)
			(stroke
				(width 0.1)
				(type default)
			)
			(layer "F.Fab")
		)
		(fp_line
			(start 0.67945 0.3048)
			(end 0.120396 0.3048)
			(stroke
				(width 0.1)
				(type default)
			)
			(layer "F.Fab")
		)
		(fp_line
			(start 0.120396 0.3048)
			(end 0.120396 0.2794)
			(stroke
				(width 0.1)
				(type default)
			)
			(layer "F.Fab")
		)
		(fp_line
			(start -0.12065 0.3048)
			(end -0.67945 0.3048)
			(stroke
				(width 0.1)
				(type default)
			)
			(layer "F.Fab")
		)
		(fp_line
			(start -0.67945 0.3048)
			(end -0.67945 -0.305054)
			(stroke
				(width 0.1)
				(type default)
			)
			(layer "F.Fab")
		)
		(pad "1" smd circle
			(at -0.40005 0 90)
			(size 0 0)
			(layers "F.Cu" "F.Mask" "F.Paste")
			(net "SSD11_PWRDIS_BIC")
		)
		(pad "2" smd circle
			(at 0.40005 0 90)
			(size 0 0)
			(layers "F.Cu" "F.Mask" "F.Paste")
			(net "SSD11_PWRDIS_BIC_R")
		)
	)
	(footprint ""
		(layer "F.Cu")
		(at 262.726678 -53.697124 -90)
		(property "Reference" "PC580"
			(at 0 0 270)
			(layer "F.SilkS")
			(hide yes)
			(effects
				(font
					(size 1.27 1.27)
				)
			)
		)
		(property "Value" ""
			(at 0 0 270)
			(layer "F.Fab")
			(effects
				(font
					(size 1.27 1.27)
				)
			)
		)
		(duplicate_pad_numbers_are_jumpers no)
		(fp_line
			(start -0.7874 0.4064)
			(end -0.7874 -0.4064)
			(stroke
				(width 0.1524)
				(type default)
			)
			(layer "F.SilkS")
		)
		(fp_line
			(start 0.7874 0.4064)
			(end -0.7874 0.4064)
			(stroke
				(width 0.1524)
				(type default)
			)
			(layer "F.SilkS")
		)
		(fp_line
			(start -0.7874 -0.4064)
			(end 0.7874 -0.4064)
			(stroke
				(width 0.1524)
				(type default)
			)
			(layer "F.SilkS")
		)
		(fp_line
			(start 0.7874 -0.4064)
			(end 0.7874 0.4064)
			(stroke
				(width 0.1524)
				(type default)
			)
			(layer "F.SilkS")
		)
		(fp_line
			(start -0.67945 0.3048)
			(end -0.67945 -0.305054)
			(stroke
				(width 0.1)
				(type default)
			)
			(layer "F.Fab")
		)
		(fp_line
			(start -0.12065 0.3048)
			(end -0.67945 0.3048)
			(stroke
				(width 0.1)
				(type default)
			)
			(layer "F.Fab")
		)
		(fp_line
			(start 0.120396 0.3048)
			(end 0.120396 0.2794)
			(stroke
				(width 0.1)
				(type default)
			)
			(layer "F.Fab")
		)
		(fp_line
			(start 0.67945 0.3048)
			(end 0.120396 0.3048)
			(stroke
				(width 0.1)
				(type default)
			)
			(layer "F.Fab")
		)
		(fp_line
			(start -0.12065 0.2794)
			(end -0.12065 0.3048)
			(stroke
				(width 0.1)
				(type default)
			)
			(layer "F.Fab")
		)
		(fp_line
			(start 0.120396 0.2794)
			(end -0.12065 0.2794)
			(stroke
				(width 0.1)
				(type default)
			)
			(layer "F.Fab")
		)
		(fp_line
			(start -0.12065 -0.2794)
			(end 0.12065 -0.2794)
			(stroke
				(width 0.1)
				(type default)
			)
			(layer "F.Fab")
		)
		(fp_line
			(start 0.12065 -0.2794)
			(end 0.12065 -0.3048)
			(stroke
				(width 0.1)
				(type default)
			)
			(layer "F.Fab")
		)
		(fp_line
			(start 0.12065 -0.3048)
			(end 0.67945 -0.3048)
			(stroke
				(width 0.1)
				(type default)
			)
			(layer "F.Fab")
		)
		(fp_line
			(start 0.67945 -0.3048)
			(end 0.67945 0.3048)
			(stroke
				(width 0.1)
				(type default)
			)
			(layer "F.Fab")
		)
		(fp_line
			(start -0.67945 -0.305054)
			(end -0.12065 -0.305054)
			(stroke
				(width 0.1)
				(type default)
			)
			(layer "F.Fab")
		)
		(fp_line
			(start -0.12065 -0.305054)
			(end -0.12065 -0.2794)
			(stroke
				(width 0.1)
				(type default)
			)
			(layer "F.Fab")
		)
		(pad "1" smd circle
			(at -0.40005 0 270)
			(size 0 0)
			(layers "F.Cu" "F.Mask" "F.Paste")
			(net "P3V3_AUX")
		)
		(pad "2" smd circle
			(at 0.40005 0 270)
			(size 0 0)
			(layers "F.Cu" "F.Mask" "F.Paste")
			(net "GND")
		)
	)
	(footprint ""
		(layer "F.Cu")
		(at 193.453766 -83.932268 90)
		(property "Reference" "C412"
			(at 0 0 90)
			(layer "F.SilkS")
			(hide yes)
			(effects
				(font
					(size 1.27 1.27)
				)
			)
		)
		(property "Value" ""
			(at 0 0 90)
			(layer "F.Fab")
			(effects
				(font
					(size 1.27 1.27)
				)
			)
		)
		(duplicate_pad_numbers_are_jumpers no)
		(fp_line
			(start 0.7874 -0.4064)
			(end 0.7874 0.4064)
			(stroke
				(width 0.1524)
				(type default)
			)
			(layer "F.SilkS")
		)
		(fp_line
			(start -0.7874 -0.4064)
			(end 0.7874 -0.4064)
			(stroke
				(width 0.1524)
				(type default)
			)
			(layer "F.SilkS")
		)
		(fp_line
			(start 0.7874 0.4064)
			(end -0.7874 0.4064)
			(stroke
				(width 0.1524)
				(type default)
			)
			(layer "F.SilkS")
		)
		(fp_line
			(start -0.7874 0.4064)
			(end -0.7874 -0.4064)
			(stroke
				(width 0.1524)
				(type default)
			)
			(layer "F.SilkS")
		)
		(fp_line
			(start -0.12065 -0.305054)
			(end -0.12065 -0.2794)
			(stroke
				(width 0.1)
				(type default)
			)
			(layer "F.Fab")
		)
		(fp_line
			(start -0.67945 -0.305054)
			(end -0.12065 -0.305054)
			(stroke
				(width 0.1)
				(type default)
			)
			(layer "F.Fab")
		)
		(fp_line
			(start 0.67945 -0.3048)
			(end 0.67945 0.3048)
			(stroke
				(width 0.1)
				(type default)
			)
			(layer "F.Fab")
		)
		(fp_line
			(start 0.12065 -0.3048)
			(end 0.67945 -0.3048)
			(stroke
				(width 0.1)
				(type default)
			)
			(layer "F.Fab")
		)
		(fp_line
			(start 0.12065 -0.2794)
			(end 0.12065 -0.3048)
			(stroke
				(width 0.1)
				(type default)
			)
			(layer "F.Fab")
		)
		(fp_line
			(start -0.12065 -0.2794)
			(end 0.12065 -0.2794)
			(stroke
				(width 0.1)
				(type default)
			)
			(layer "F.Fab")
		)
		(fp_line
			(start 0.120396 0.2794)
			(end -0.12065 0.2794)
			(stroke
				(width 0.1)
				(type default)
			)
			(layer "F.Fab")
		)
		(fp_line
			(start -0.12065 0.2794)
			(end -0.12065 0.3048)
			(stroke
				(width 0.1)
				(type default)
			)
			(layer "F.Fab")
		)
		(fp_line
			(start 0.67945 0.3048)
			(end 0.120396 0.3048)
			(stroke
				(width 0.1)
				(type default)
			)
			(layer "F.Fab")
		)
		(fp_line
			(start 0.120396 0.3048)
			(end 0.120396 0.2794)
			(stroke
				(width 0.1)
				(type default)
			)
			(layer "F.Fab")
		)
		(fp_line
			(start -0.12065 0.3048)
			(end -0.67945 0.3048)
			(stroke
				(width 0.1)
				(type default)
			)
			(layer "F.Fab")
		)
		(fp_line
			(start -0.67945 0.3048)
			(end -0.67945 -0.305054)
			(stroke
				(width 0.1)
				(type default)
			)
			(layer "F.Fab")
		)
		(pad "1" smd circle
			(at -0.40005 0 90)
			(size 0 0)
			(layers "F.Cu" "F.Mask" "F.Paste")
			(net "P3V3_AUX")
		)
		(pad "2" smd circle
			(at 0.40005 0 90)
			(size 0 0)
			(layers "F.Cu" "F.Mask" "F.Paste")
			(net "GND")
		)
	)
)
